(kicad_pcb
	(version 20260206)
	(generator "pcbnew")
	(generator_version "10.0")
	(general
		(thickness 1.6)
		(legacy_teardrops no)
	)
	(paper "A4")
	(title_block
		(title "01162023_DA0F0TEBIF0_F0T_Expander_BD_F_brd_V02_OCP.brd")
		(comment 1 "Grand Teton / footprints 5309-5312 of 9728")
	)
	(layers
		(0 "F.Cu" signal "TOP")
		(4 "In1.Cu" signal "GND")
		(6 "In2.Cu" signal "VCC")
		(8 "In3.Cu" signal "VCC1")
		(10 "In4.Cu" signal "GND1")
		(12 "In5.Cu" signal "IN1")
		(14 "In6.Cu" signal "GND2")
		(16 "In7.Cu" signal "IN2")
		(18 "In8.Cu" signal "GND3")
		(20 "In9.Cu" signal "IN3")
		(22 "In10.Cu" signal "GND4")
		(24 "In11.Cu" signal "IN4")
		(26 "In12.Cu" signal "GND5")
		(28 "In13.Cu" signal "IN5")
		(30 "In14.Cu" signal "GND6")
		(32 "In15.Cu" signal "IN6")
		(34 "In16.Cu" signal "GND7")
		(2 "B.Cu" signal "BOTTOM")
		(9 "F.Adhes" user "F.Adhesive")
		(11 "B.Adhes" user "B.Adhesive")
		(13 "F.Paste" user "Package Geometry/Pastemask Top")
		(15 "B.Paste" user "Package Geometry/Pastemask Bottom")
		(5 "F.SilkS" user "Ref Des/Silkscreen Top")
		(7 "B.SilkS" user "Ref Des/Silkscreen Bottom")
		(1 "F.Mask" user "Board Geometry/Soldermask Top")
		(3 "B.Mask" user "Board Geometry/Soldermask Bottom")
		(17 "Dwgs.User" user "User.Drawings")
		(19 "Cmts.User" user "User.Comments")
		(21 "Eco1.User" user "User.Eco1")
		(23 "Eco2.User" user "User.Eco2")
		(25 "Edge.Cuts" user "Board Geometry/Outline")
		(27 "Margin" user)
		(31 "F.CrtYd" user "Package Geometry/Place Bound Top")
		(29 "B.CrtYd" user "Package Geometry/Place Bound Bottom")
		(35 "F.Fab" user "Ref Des/Assembly Top")
		(33 "B.Fab" user "Ref Des/Assembly Bottom")
	)
	(footprint ""
		(layer "F.Cu")
		(at 11.593322 -116.311426 -90)
		(property "Reference" "Q212"
			(at 0.030226 1.990852 90)
			(unlocked yes)
			(layer "F.SilkS")
			(effects
				(font
					(size 0.7874 0.5842)
					(thickness 0.1524)
				)
			)
		)
		(property "Value" ""
			(at 0 0 270)
			(layer "F.Fab")
			(effects
				(font
					(size 1.27 1.27)
				)
			)
		)
		(duplicate_pad_numbers_are_jumpers no)
		(fp_line
			(start -1.376172 1.199896)
			(end -1.376172 -1.199896)
			(stroke
				(width 0.1524)
				(type default)
			)
			(layer "F.SilkS")
		)
		(fp_line
			(start 1.376172 1.199896)
			(end -1.376172 1.199896)
			(stroke
				(width 0.1524)
				(type default)
			)
			(layer "F.SilkS")
		)
		(fp_line
			(start 0 -0.762)
			(end 0.508 -1.199896)
			(stroke
				(width 0.1524)
				(type default)
			)
			(layer "F.SilkS")
		)
		(fp_line
			(start -1.376172 -1.199896)
			(end -0.508 -1.199896)
			(stroke
				(width 0.1524)
				(type default)
			)
			(layer "F.SilkS")
		)
		(fp_line
			(start -0.508 -1.199896)
			(end 0 -0.762)
			(stroke
				(width 0.1524)
				(type default)
			)
			(layer "F.SilkS")
		)
		(fp_line
			(start 0.508 -1.199896)
			(end 1.376172 -1.199896)
			(stroke
				(width 0.1524)
				(type default)
			)
			(layer "F.SilkS")
		)
		(fp_line
			(start 1.376172 -1.199896)
			(end 1.376172 1.199896)
			(stroke
				(width 0.1524)
				(type default)
			)
			(layer "F.SilkS")
		)
		(fp_poly
			(pts
				(xy -1.141984 -1.262126) (xy -1.411478 -2.070354) (xy -1.950212 -1.531366)
			)
			(stroke
				(width 0)
				(type default)
			)
			(fill yes)
			(layer "F.SilkS")
		)
		(fp_line
			(start -0.674878 1.100074)
			(end -0.674878 -1.100074)
			(stroke
				(width 0.1)
				(type default)
			)
			(layer "F.Fab")
		)
		(fp_line
			(start 0.674878 1.100074)
			(end -0.674878 1.100074)
			(stroke
				(width 0.1)
				(type default)
			)
			(layer "F.Fab")
		)
		(fp_line
			(start -0.674878 -1.100074)
			(end 0.674878 -1.100074)
			(stroke
				(width 0.1)
				(type default)
			)
			(layer "F.Fab")
		)
		(fp_line
			(start 0.674878 -1.100074)
			(end 0.674878 1.100074)
			(stroke
				(width 0.1)
				(type default)
			)
			(layer "F.Fab")
		)
		(fp_poly
			(pts
				(xy -1.4605 -0.7493) (xy -2.2225 -1.1303) (xy -2.2225 -0.3683)
			)
			(stroke
				(width 0)
				(type default)
			)
			(fill yes)
			(layer "F.Fab")
		)
		(pad "1" smd rect
			(at -0.899922 -0.750062 180)
			(size 0.6096 0.6096)
			(layers "F.Cu" "F.Mask" "F.Paste")
			(net "GND")
		)
		(pad "2" smd rect
			(at -0.899922 0 180)
			(size 0.4064 0.6096)
			(layers "F.Cu" "F.Mask" "F.Paste")
			(net "P3V3_NIC0_PG_G1")
		)
		(pad "3" smd rect
			(at -0.899922 0.750062 180)
			(size 0.6096 0.6096)
			(layers "F.Cu" "F.Mask" "F.Paste")
			(net "PWRGD_P3V3_NIC0_D")
		)
		(pad "4" smd rect
			(at 0.899922 0.750062 180)
			(size 0.6096 0.6096)
			(layers "F.Cu" "F.Mask" "F.Paste")
			(net "GND")
		)
		(pad "5" smd rect
			(at 0.899922 0 180)
			(size 0.4064 0.6096)
			(layers "F.Cu" "F.Mask" "F.Paste")
			(net "P3V3_NIC0_PG_G2")
		)
		(pad "6" smd rect
			(at 0.899922 -0.750062 180)
			(size 0.6096 0.6096)
			(layers "F.Cu" "F.Mask" "F.Paste")
			(net "P3V3_NIC0_PG_G2")
		)
	)
	(footprint ""
		(layer "F.Cu")
		(at 361.745784 -114.385852 -90)
		(property "Reference" "PC909"
			(at 0 0 270)
			(layer "F.SilkS")
			(hide yes)
			(effects
				(font
					(size 1.27 1.27)
				)
			)
		)
		(property "Value" ""
			(at 0 0 270)
			(layer "F.Fab")
			(effects
				(font
					(size 1.27 1.27)
				)
			)
		)
		(duplicate_pad_numbers_are_jumpers no)
		(fp_line
			(start -0.7874 0.4064)
			(end -0.7874 -0.4064)
			(stroke
				(width 0.1524)
				(type default)
			)
			(layer "F.SilkS")
		)
		(fp_line
			(start 0.7874 0.4064)
			(end -0.7874 0.4064)
			(stroke
				(width 0.1524)
				(type default)
			)
			(layer "F.SilkS")
		)
		(fp_line
			(start -0.7874 -0.4064)
			(end 0.7874 -0.4064)
			(stroke
				(width 0.1524)
				(type default)
			)
			(layer "F.SilkS")
		)
		(fp_line
			(start 0.7874 -0.4064)
			(end 0.7874 0.4064)
			(stroke
				(width 0.1524)
				(type default)
			)
			(layer "F.SilkS")
		)
		(fp_line
			(start -0.67945 0.3048)
			(end -0.67945 -0.305054)
			(stroke
				(width 0.1)
				(type default)
			)
			(layer "F.Fab")
		)
		(fp_line
			(start -0.12065 0.3048)
			(end -0.67945 0.3048)
			(stroke
				(width 0.1)
				(type default)
			)
			(layer "F.Fab")
		)
		(fp_line
			(start 0.120396 0.3048)
			(end 0.120396 0.2794)
			(stroke
				(width 0.1)
				(type default)
			)
			(layer "F.Fab")
		)
		(fp_line
			(start 0.67945 0.3048)
			(end 0.120396 0.3048)
			(stroke
				(width 0.1)
				(type default)
			)
			(layer "F.Fab")
		)
		(fp_line
			(start -0.12065 0.2794)
			(end -0.12065 0.3048)
			(stroke
				(width 0.1)
				(type default)
			)
			(layer "F.Fab")
		)
		(fp_line
			(start 0.120396 0.2794)
			(end -0.12065 0.2794)
			(stroke
				(width 0.1)
				(type default)
			)
			(layer "F.Fab")
		)
		(fp_line
			(start -0.12065 -0.2794)
			(end 0.12065 -0.2794)
			(stroke
				(width 0.1)
				(type default)
			)
			(layer "F.Fab")
		)
		(fp_line
			(start 0.12065 -0.2794)
			(end 0.12065 -0.3048)
			(stroke
				(width 0.1)
				(type default)
			)
			(layer "F.Fab")
		)
		(fp_line
			(start 0.12065 -0.3048)
			(end 0.67945 -0.3048)
			(stroke
				(width 0.1)
				(type default)
			)
			(layer "F.Fab")
		)
		(fp_line
			(start 0.67945 -0.3048)
			(end 0.67945 0.3048)
			(stroke
				(width 0.1)
				(type default)
			)
			(layer "F.Fab")
		)
		(fp_line
			(start -0.67945 -0.305054)
			(end -0.12065 -0.305054)
			(stroke
				(width 0.1)
				(type default)
			)
			(layer "F.Fab")
		)
		(fp_line
			(start -0.12065 -0.305054)
			(end -0.12065 -0.2794)
			(stroke
				(width 0.1)
				(type default)
			)
			(layer "F.Fab")
		)
		(pad "1" smd circle
			(at -0.40005 0 270)
			(size 0 0)
			(layers "F.Cu" "F.Mask" "F.Paste")
			(net "P3V3_AUX")
		)
		(pad "2" smd circle
			(at 0.40005 0 270)
			(size 0 0)
			(layers "F.Cu" "F.Mask" "F.Paste")
			(net "GND")
		)
	)
	(footprint ""
		(layer "F.Cu")
		(at 19.352006 -408.505152 90)
		(property "Reference" "U328"
			(at -3.6576 -3.190748 90)
			(unlocked yes)
			(layer "F.SilkS")
			(effects
				(font
					(size 0.7874 0.5842)
					(thickness 0.1524)
				)
				(justify left)
			)
		)
		(property "Value" ""
			(at 0 0 90)
			(layer "F.Fab")
			(effects
				(font
					(size 1.27 1.27)
				)
			)
		)
		(duplicate_pad_numbers_are_jumpers no)
		(fp_line
			(start 3.447796 -2.500122)
			(end 1.484122 -2.500122)
			(stroke
				(width 0.1524)
				(type default)
			)
			(layer "F.SilkS")
		)
		(fp_line
			(start 1.484122 -2.500122)
			(end 0 -1.016)
			(stroke
				(width 0.1524)
				(type default)
			)
			(layer "F.SilkS")
		)
		(fp_line
			(start -1.484122 -2.500122)
			(end -3.447796 -2.500122)
			(stroke
				(width 0.1524)
				(type default)
			)
			(layer "F.SilkS")
		)
		(fp_line
			(start -3.447796 -2.500122)
			(end -3.447796 2.500122)
			(stroke
				(width 0.1524)
				(type default)
			)
			(layer "F.SilkS")
		)
		(fp_line
			(start 0 -1.016)
			(end -1.484122 -2.500122)
			(stroke
				(width 0.1524)
				(type default)
			)
			(layer "F.SilkS")
		)
		(fp_line
			(start 3.447796 2.500122)
			(end 3.447796 -2.500122)
			(stroke
				(width 0.1524)
				(type default)
			)
			(layer "F.SilkS")
		)
		(fp_line
			(start -3.447796 2.500122)
			(end 3.447796 2.500122)
			(stroke
				(width 0.1524)
				(type default)
			)
			(layer "F.SilkS")
		)
		(fp_poly
			(pts
				(xy -4.088892 -3.269234) (xy -4.807204 -2.550922) (xy -3.729736 -2.191766)
			)
			(stroke
				(width 0)
				(type default)
			)
			(fill yes)
			(layer "F.SilkS")
		)
		(fp_line
			(start 1.999996 -2.500122)
			(end -1.999996 -2.500122)
			(stroke
				(width 0.1)
				(type default)
			)
			(layer "F.Fab")
		)
		(fp_line
			(start -1.999996 -2.500122)
			(end -1.999996 2.500122)
			(stroke
				(width 0.1)
				(type default)
			)
			(layer "F.Fab")
		)
		(fp_line
			(start 1.999996 2.500122)
			(end 1.999996 -2.500122)
			(stroke
				(width 0.1)
				(type default)
			)
			(layer "F.Fab")
		)
		(fp_line
			(start -1.999996 2.500122)
			(end 1.999996 2.500122)
			(stroke
				(width 0.1)
				(type default)
			)
			(layer "F.Fab")
		)
		(fp_poly
			(pts
				(xy -4.5974 -2.413) (xy -4.5974 -1.397) (xy -3.5814 -1.905)
			)
			(stroke
				(width 0)
				(type default)
			)
			(fill yes)
			(layer "F.Fab")
		)
		(pad "1" smd rect
			(at -2.649982 -1.905)
			(size 0.6096 1.3208)
			(layers "F.Cu" "F.Mask" "F.Paste")
			(net "SMB_LM75_0_SDA")
		)
		(pad "2" smd rect
			(at -2.649982 -0.635)
			(size 0.6096 1.3208)
			(layers "F.Cu" "F.Mask" "F.Paste")
			(net "SMB_LM75_0_SCL")
		)
		(pad "3" smd rect
			(at -2.649982 0.635)
			(size 0.6096 1.3208)
			(layers "F.Cu" "F.Mask" "F.Paste")
			(net "Net_405")
		)
		(pad "4" smd rect
			(at -2.649982 1.905)
			(size 0.6096 1.3208)
			(layers "F.Cu" "F.Mask" "F.Paste")
			(net "GND")
		)
		(pad "5" smd rect
			(at 2.649982 1.905)
			(size 0.6096 1.3208)
			(layers "F.Cu" "F.Mask" "F.Paste")
			(net "LM75_0_A2")
		)
		(pad "6" smd rect
			(at 2.649982 0.635)
			(size 0.6096 1.3208)
			(layers "F.Cu" "F.Mask" "F.Paste")
			(net "LM75_0_A1")
		)
		(pad "7" smd rect
			(at 2.649982 -0.635)
			(size 0.6096 1.3208)
			(layers "F.Cu" "F.Mask" "F.Paste")
			(net "LM75_0_A0")
		)
		(pad "8" smd rect
			(at 2.649982 -1.905)
			(size 0.6096 1.3208)
			(layers "F.Cu" "F.Mask" "F.Paste")
			(net "P3V3_AUX")
		)
	)
	(footprint ""
		(layer "F.Cu")
		(at 90.0176 -304.036476 90)
		(property "Reference" "R1248"
			(at 0 0 90)
			(layer "F.SilkS")
			(hide yes)
			(effects
				(font
					(size 1.27 1.27)
				)
			)
		)
		(property "Value" ""
			(at 0 0 90)
			(layer "F.Fab")
			(effects
				(font
					(size 1.27 1.27)
				)
			)
		)
		(duplicate_pad_numbers_are_jumpers no)
		(fp_line
			(start 0.7874 -0.4064)
			(end 0.7874 0.4064)
			(stroke
				(width 0.1524)
				(type default)
			)
			(layer "F.SilkS")
		)
		(fp_line
			(start -0.7874 -0.4064)
			(end 0.7874 -0.4064)
			(stroke
				(width 0.1524)
				(type default)
			)
			(layer "F.SilkS")
		)
		(fp_line
			(start 0.7874 0.4064)
			(end -0.7874 0.4064)
			(stroke
				(width 0.1524)
				(type default)
			)
			(layer "F.SilkS")
		)
		(fp_line
			(start -0.7874 0.4064)
			(end -0.7874 -0.4064)
			(stroke
				(width 0.1524)
				(type default)
			)
			(layer "F.SilkS")
		)
		(fp_line
			(start -0.12065 -0.305054)
			(end -0.12065 -0.2794)
			(stroke
				(width 0.1)
				(type default)
			)
			(layer "F.Fab")
		)
		(fp_line
			(start -0.67945 -0.305054)
			(end -0.12065 -0.305054)
			(stroke
				(width 0.1)
				(type default)
			)
			(layer "F.Fab")
		)
		(fp_line
			(start 0.67945 -0.3048)
			(end 0.67945 0.3048)
			(stroke
				(width 0.1)
				(type default)
			)
			(layer "F.Fab")
		)
		(fp_line
			(start 0.12065 -0.3048)
			(end 0.67945 -0.3048)
			(stroke
				(width 0.1)
				(type default)
			)
			(layer "F.Fab")
		)
		(fp_line
			(start 0.12065 -0.2794)
			(end 0.12065 -0.3048)
			(stroke
				(width 0.1)
				(type default)
			)
			(layer "F.Fab")
		)
		(fp_line
			(start -0.12065 -0.2794)
			(end 0.12065 -0.2794)
			(stroke
				(width 0.1)
				(type default)
			)
			(layer "F.Fab")
		)
		(fp_line
			(start 0.120396 0.2794)
			(end -0.12065 0.2794)
			(stroke
				(width 0.1)
				(type default)
			)
			(layer "F.Fab")
		)
		(fp_line
			(start -0.12065 0.2794)
			(end -0.12065 0.3048)
			(stroke
				(width 0.1)
				(type default)
			)
			(layer "F.Fab")
		)
		(fp_line
			(start 0.67945 0.3048)
			(end 0.120396 0.3048)
			(stroke
				(width 0.1)
				(type default)
			)
			(layer "F.Fab")
		)
		(fp_line
			(start 0.120396 0.3048)
			(end 0.120396 0.2794)
			(stroke
				(width 0.1)
				(type default)
			)
			(layer "F.Fab")
		)
		(fp_line
			(start -0.12065 0.3048)
			(end -0.67945 0.3048)
			(stroke
				(width 0.1)
				(type default)
			)
			(layer "F.Fab")
		)
		(fp_line
			(start -0.67945 0.3048)
			(end -0.67945 -0.305054)
			(stroke
				(width 0.1)
				(type default)
			)
			(layer "F.Fab")
		)
		(pad "1" smd circle
			(at -0.40005 0 90)
			(size 0 0)
			(layers "F.Cu" "F.Mask" "F.Paste")
			(net "GND")
		)
		(pad "2" smd circle
			(at 0.40005 0 90)
			(size 0 0)
			(layers "F.Cu" "F.Mask" "F.Paste")
			(net "PEX0_SPARE3")
		)
	)
)
